(kicad_pcb
	(version 20260206)
	(generator "pcbnew")
	(generator_version "10.0")
	(general
		(thickness 1.6)
		(legacy_teardrops no)
	)
	(paper "A4")
	(title_block
		(title "Bryce Canyon_R.DPB_16317-1_OCP.brd")
		(comment 1 "Bryce Canyon / footprints 104-110 of 2099")
	)
	(layers
		(0 "F.Cu" signal "TOP")
		(4 "In1.Cu" signal "L2GND")
		(6 "In2.Cu" signal "L3")
		(8 "In3.Cu" signal "L4VCC")
		(10 "In4.Cu" signal "L5VCC")
		(12 "In5.Cu" signal "L6")
		(14 "In6.Cu" signal "L7GND")
		(2 "B.Cu" signal "BOTTOM")
		(9 "F.Adhes" user "F.Adhesive")
		(11 "B.Adhes" user "B.Adhesive")
		(13 "F.Paste" user "Package Geometry/Pastemask Top")
		(15 "B.Paste" user "Package Geometry/Pastemask Bottom")
		(5 "F.SilkS" user "Ref Des/Silkscreen Top")
		(7 "B.SilkS" user "Ref Des/Silkscreen Bottom")
		(1 "F.Mask" user "Board Geometry/Soldermask Top")
		(3 "B.Mask" user "Board Geometry/Soldermask Bottom")
		(17 "Dwgs.User" user "User.Drawings")
		(19 "Cmts.User" user "User.Comments")
		(21 "Eco1.User" user "User.Eco1")
		(23 "Eco2.User" user "User.Eco2")
		(25 "Edge.Cuts" user "Board Geometry/Outline")
		(27 "Margin" user)
		(31 "F.CrtYd" user "Package Geometry/Place Bound Top")
		(29 "B.CrtYd" user "Package Geometry/Place Bound Bottom")
		(35 "F.Fab" user "Ref Des/Assembly Top")
		(33 "B.Fab" user "Ref Des/Assembly Bottom")
	)
	(footprint ""
		(layer "F.Cu")
		(at 213.852506 -98.58121 180)
		(property "Reference" "R354"
			(at 0 0 180)
			(layer "F.SilkS")
			(hide yes)
			(effects
				(font
					(size 1.27 1.27)
				)
			)
		)
		(property "Value" "0R2J-2-GP"
			(at 0.064008 -3.993896 180)
			(unlocked yes)
			(layer "F.Fab")
			(hide yes)
			(effects
				(font
					(size 1.016 1.016)
					(thickness 0.1524)
				)
			)
		)
		(property "Device Type" "R402H16"
			(at 0.064008 -5.517896 180)
			(unlocked yes)
			(layer "F.Fab")
			(hide yes)
			(effects
				(font
					(size 1.016 1.016)
					(thickness 0.1524)
				)
			)
		)
		(duplicate_pad_numbers_are_jumpers no)
		(fp_line
			(start 0.508 -0.9398)
			(end -0.508 -0.9398)
			(stroke
				(width 0.1524)
				(type default)
			)
			(layer "F.SilkS")
		)
		(fp_line
			(start -0.508 -0.9398)
			(end -0.508 0.9398)
			(stroke
				(width 0.1524)
				(type default)
			)
			(layer "F.SilkS")
		)
		(fp_rect
			(start -0.508 0.9398)
			(end 0.508 -0.9398)
			(stroke
				(width 0)
				(type default)
			)
			(fill no)
			(layer "F.CrtYd")
		)
		(fp_rect
			(start -0.508 0.9398)
			(end 0.508 -0.9398)
			(stroke
				(width 0)
				(type default)
			)
			(fill no)
			(layer "F.Fab")
		)
		(pad "1" smd custom
			(at 0 -0.4445 180)
			(size 0.1397 0.1397)
			(layers "F.Cu" "F.Mask" "F.Paste")
			(net "I2C_CLIP_A_SDA")
			(options
				(clearance outline)
				(anchor circle)
			)
			(primitives
				(gr_poly
					(pts
						(arc
							(start -0.1778 -0.2794)
							(mid -0.249642 -0.249642)
							(end -0.2794 -0.1778)
						)
						(arc
							(start -0.2794 0.1778)
							(mid -0.249642 0.249642)
							(end -0.1778 0.2794)
						)
						(arc
							(start 0.1778 0.2794)
							(mid 0.249642 0.249642)
							(end 0.2794 0.1778)
						)
						(arc
							(start 0.2794 -0.1778)
							(mid 0.249642 -0.249642)
							(end 0.1778 -0.2794)
						)
					)
					(width 0)
					(fill yes)
				)
			)
		)
		(pad "2" smd custom
			(at 0 0.4445 180)
			(size 0.1397 0.1397)
			(layers "F.Cu" "F.Mask" "F.Paste")
			(net "I2C_CLIP_B_SDA")
			(options
				(clearance outline)
				(anchor circle)
			)
			(primitives
				(gr_poly
					(pts
						(arc
							(start -0.1778 -0.2794)
							(mid -0.249642 -0.249642)
							(end -0.2794 -0.1778)
						)
						(arc
							(start -0.2794 0.1778)
							(mid -0.249642 0.249642)
							(end -0.1778 0.2794)
						)
						(arc
							(start 0.1778 0.2794)
							(mid 0.249642 0.249642)
							(end 0.2794 0.1778)
						)
						(arc
							(start 0.2794 -0.1778)
							(mid 0.249642 -0.249642)
							(end 0.1778 -0.2794)
						)
					)
					(width 0)
					(fill yes)
				)
			)
		)
	)
	(footprint ""
		(layer "F.Cu")
		(at 398.018 -138.938 -90)
		(property "Reference" "Q93"
			(at 0 0 270)
			(layer "F.SilkS")
			(hide yes)
			(effects
				(font
					(size 1.27 1.27)
				)
			)
		)
		(property "Value" "AO4406AL-GP"
			(at -3.707384 -1.5367 270)
			(unlocked yes)
			(layer "F.Fab")
			(hide yes)
			(effects
				(font
					(size 1.016 1.016)
					(thickness 0.1524)
				)
			)
		)
		(property "Device Type" "SOIC8H69"
			(at -3.707384 -3.0607 270)
			(unlocked yes)
			(layer "F.Fab")
			(hide yes)
			(effects
				(font
					(size 1.016 1.016)
					(thickness 0.1524)
				)
			)
		)
		(duplicate_pad_numbers_are_jumpers no)
		(fp_line
			(start -2.6289 3.4417)
			(end -2.6289 1.4732)
			(stroke
				(width 0.381)
				(type default)
			)
			(layer "F.SilkS")
		)
		(fp_line
			(start -2.7432 1.4224)
			(end -2.6416 1.4224)
			(stroke
				(width 0.1524)
				(type default)
			)
			(layer "F.SilkS")
		)
		(fp_line
			(start -2.7432 1.4224)
			(end 2.1336 1.4224)
			(stroke
				(width 0.1524)
				(type default)
			)
			(layer "F.SilkS")
		)
		(fp_line
			(start 2.1336 1.4224)
			(end 2.1336 -1.4224)
			(stroke
				(width 0.1524)
				(type default)
			)
			(layer "F.SilkS")
		)
		(fp_line
			(start -2.1844 -0.0508)
			(end -2.7178 0.508)
			(stroke
				(width 0.1524)
				(type default)
			)
			(layer "F.SilkS")
		)
		(fp_line
			(start -2.7178 -0.508)
			(end -2.1844 -0.0508)
			(stroke
				(width 0.1524)
				(type default)
			)
			(layer "F.SilkS")
		)
		(fp_line
			(start -2.7432 -1.4224)
			(end -2.7432 1.4224)
			(stroke
				(width 0.1524)
				(type default)
			)
			(layer "F.SilkS")
		)
		(fp_line
			(start 2.1336 -1.4224)
			(end -2.7432 -1.4224)
			(stroke
				(width 0.1524)
				(type default)
			)
			(layer "F.SilkS")
		)
		(fp_poly
			(pts
				(xy -2.2098 -1.4224) (xy -2.2098 1.4224) (xy 2.2098 1.4224) (xy 2.2098 -1.4224)
			)
			(stroke
				(width 0)
				(type default)
			)
			(fill yes)
			(layer "F.SilkS")
		)
		(fp_rect
			(start -2.450084 2.999994)
			(end 2.450084 -2.999994)
			(stroke
				(width 0)
				(type default)
			)
			(fill no)
			(layer "F.CrtYd")
		)
		(fp_poly
			(pts
				(xy -2.8194 3.6322) (xy -2.8194 -3.6322) (xy 2.8194 -3.6322) (xy 2.8194 1.18364) (xy 2.450084 1.18364)
				(xy 2.450084 -2.999994) (xy -2.450084 -2.999994) (xy -2.450084 2.999994) (xy 2.450084 2.999994)
				(xy 2.450084 1.18618) (xy 2.8194 1.18618) (xy 2.8194 3.6322)
			)
			(stroke
				(width 0)
				(type default)
			)
			(fill no)
			(layer "F.CrtYd")
		)
		(fp_rect
			(start -2.8194 3.6322)
			(end 2.8194 -3.6322)
			(stroke
				(width 0)
				(type default)
			)
			(fill no)
			(layer "F.Fab")
		)
		(pad "1" smd rect
			(at -1.905 2.54 270)
			(size 0.635 1.651)
			(layers "F.Cu" "F.Mask" "F.Paste")
			(net "P5V_HDD20")
		)
		(pad "2" smd rect
			(at -0.635 2.54 270)
			(size 0.635 1.651)
			(layers "F.Cu" "F.Mask" "F.Paste")
			(net "P5V_HDD20")
		)
		(pad "3" smd rect
			(at 0.635 2.54 270)
			(size 0.635 1.651)
			(layers "F.Cu" "F.Mask" "F.Paste")
			(net "P5V_HDD20")
		)
		(pad "4" smd rect
			(at 1.905 2.54 270)
			(size 0.635 1.651)
			(layers "F.Cu" "F.Mask" "F.Paste")
			(net "SW_HDD_P20")
		)
		(pad "5" smd rect
			(at 1.905 -2.54 270)
			(size 0.635 1.651)
			(layers "F.Cu" "F.Mask" "F.Paste")
			(net "P5V_B_3")
		)
		(pad "6" smd rect
			(at 0.635 -2.54 270)
			(size 0.635 1.651)
			(layers "F.Cu" "F.Mask" "F.Paste")
			(net "P5V_B_3")
		)
		(pad "7" smd rect
			(at -0.635 -2.54 270)
			(size 0.635 1.651)
			(layers "F.Cu" "F.Mask" "F.Paste")
			(net "P5V_B_3")
		)
		(pad "8" smd rect
			(at -1.905 -2.54 270)
			(size 0.635 1.651)
			(layers "F.Cu" "F.Mask" "F.Paste")
			(net "P5V_B_3")
		)
	)
	(footprint ""
		(layer "F.Cu")
		(at 338.455 -27.813 -90)
		(property "Reference" "R775"
			(at 0 0 270)
			(layer "F.SilkS")
			(hide yes)
			(effects
				(font
					(size 1.27 1.27)
				)
			)
		)
		(property "Value" "300KR2F-GP"
			(at 0.064008 -3.993896 270)
			(unlocked yes)
			(layer "F.Fab")
			(hide yes)
			(effects
				(font
					(size 1.016 1.016)
					(thickness 0.1524)
				)
			)
		)
		(property "Device Type" "R402H16"
			(at 0.064008 -5.517896 270)
			(unlocked yes)
			(layer "F.Fab")
			(hide yes)
			(effects
				(font
					(size 1.016 1.016)
					(thickness 0.1524)
				)
			)
		)
		(duplicate_pad_numbers_are_jumpers no)
		(fp_line
			(start -0.508 -0.9398)
			(end -0.508 0.9398)
			(stroke
				(width 0.1524)
				(type default)
			)
			(layer "F.SilkS")
		)
		(fp_line
			(start 0.508 -0.9398)
			(end -0.508 -0.9398)
			(stroke
				(width 0.1524)
				(type default)
			)
			(layer "F.SilkS")
		)
		(fp_rect
			(start -0.508 0.9398)
			(end 0.508 -0.9398)
			(stroke
				(width 0)
				(type default)
			)
			(fill no)
			(layer "F.CrtYd")
		)
		(fp_rect
			(start -0.508 0.9398)
			(end 0.508 -0.9398)
			(stroke
				(width 0)
				(type default)
			)
			(fill no)
			(layer "F.Fab")
		)
		(pad "1" smd custom
			(at 0 -0.4445 270)
			(size 0.1397 0.1397)
			(layers "F.Cu" "F.Mask" "F.Paste")
			(net "SW_HDD_N30")
			(options
				(clearance outline)
				(anchor circle)
			)
			(primitives
				(gr_poly
					(pts
						(arc
							(start -0.1778 -0.2794)
							(mid -0.249642 -0.249642)
							(end -0.2794 -0.1778)
						)
						(arc
							(start -0.2794 0.1778)
							(mid -0.249642 0.249642)
							(end -0.1778 0.2794)
						)
						(arc
							(start 0.1778 0.2794)
							(mid 0.249642 0.249642)
							(end 0.2794 0.1778)
						)
						(arc
							(start 0.2794 -0.1778)
							(mid 0.249642 -0.249642)
							(end 0.1778 -0.2794)
						)
					)
					(width 0)
					(fill yes)
				)
			)
		)
		(pad "2" smd custom
			(at 0 0.4445 270)
			(size 0.1397 0.1397)
			(layers "F.Cu" "F.Mask" "F.Paste")
			(net "P12V_B")
			(options
				(clearance outline)
				(anchor circle)
			)
			(primitives
				(gr_poly
					(pts
						(arc
							(start -0.1778 -0.2794)
							(mid -0.249642 -0.249642)
							(end -0.2794 -0.1778)
						)
						(arc
							(start -0.2794 0.1778)
							(mid -0.249642 0.249642)
							(end -0.1778 0.2794)
						)
						(arc
							(start 0.1778 0.2794)
							(mid 0.249642 0.249642)
							(end 0.2794 0.1778)
						)
						(arc
							(start 0.2794 -0.1778)
							(mid 0.249642 -0.249642)
							(end 0.1778 -0.2794)
						)
					)
					(width 0)
					(fill yes)
				)
			)
		)
	)
	(footprint ""
		(layer "F.Cu")
		(at 180.34 -13.0302 -90)
		(property "Reference" "D29"
			(at 0 0 270)
			(layer "F.SilkS")
			(hide yes)
			(effects
				(font
					(size 1.27 1.27)
				)
			)
		)
		(property "Value" "RB551V30-GP"
			(at 0 -6.7818 270)
			(unlocked yes)
			(layer "F.Fab")
			(hide yes)
			(effects
				(font
					(size 1.016 1.016)
					(thickness 0.1524)
				)
			)
		)
		(property "Device Type" "SOD323AKH38"
			(at 0 -8.6868 270)
			(unlocked yes)
			(layer "F.Fab")
			(hide yes)
			(effects
				(font
					(size 1.016 1.016)
					(thickness 0.1524)
				)
			)
		)
		(duplicate_pad_numbers_are_jumpers no)
		(fp_line
			(start -0.889 2.159)
			(end -0.889 -1.9304)
			(stroke
				(width 0.1524)
				(type default)
			)
			(layer "F.SilkS")
		)
		(fp_line
			(start 0.889 2.159)
			(end -0.889 2.159)
			(stroke
				(width 0.1524)
				(type default)
			)
			(layer "F.SilkS")
		)
		(fp_line
			(start 0.762 2.0574)
			(end -0.762 2.0574)
			(stroke
				(width 0.508)
				(type default)
			)
			(layer "F.SilkS")
		)
		(fp_line
			(start -0.889 -1.9304)
			(end 0.889 -1.9304)
			(stroke
				(width 0.1524)
				(type default)
			)
			(layer "F.SilkS")
		)
		(fp_line
			(start 0.889 -1.9304)
			(end 0.889 2.159)
			(stroke
				(width 0.1524)
				(type default)
			)
			(layer "F.SilkS")
		)
		(fp_rect
			(start -1.016 2.3114)
			(end 1.016 -2.0066)
			(stroke
				(width 0)
				(type default)
			)
			(fill no)
			(layer "F.CrtYd")
		)
		(fp_poly
			(pts
				(xy -1.016 -2.0066) (xy 1.016 -2.0066) (xy 1.016 2.3114) (xy -1.016 2.3114)
			)
			(stroke
				(width 0)
				(type default)
			)
			(fill no)
			(layer "F.Fab")
		)
		(pad "A" smd rect
			(at 0 -1.143 270)
			(size 0.5588 1.016)
			(layers "F.Cu" "F.Mask" "F.Paste")
			(net "SW_HDD_R29")
		)
		(pad "K" smd rect
			(at 0 1.143 270)
			(size 0.5588 1.016)
			(layers "F.Cu" "F.Mask" "F.Paste")
			(net "SW_HDD_N29")
		)
	)
	(footprint ""
		(layer "F.Cu")
		(at 469.9 -255.524 90)
		(property "Reference" "C182"
			(at 0 0 90)
			(layer "F.SilkS")
			(hide yes)
			(effects
				(font
					(size 1.27 1.27)
				)
			)
		)
		(property "Value" "SCD033U25V2KX-GP"
			(at 1.1811 -2.7051 90)
			(unlocked yes)
			(layer "F.Fab")
			(hide yes)
			(effects
				(font
					(size 1.016 1.016)
					(thickness 0.1524)
				)
			)
		)
		(property "Device Type" "C402H22"
			(at 1.1811 -4.2291 90)
			(unlocked yes)
			(layer "F.Fab")
			(hide yes)
			(effects
				(font
					(size 1.016 1.016)
					(thickness 0.1524)
				)
			)
		)
		(duplicate_pad_numbers_are_jumpers no)
		(fp_rect
			(start -0.4318 0.9525)
			(end 0.4318 -0.9525)
			(stroke
				(width 0)
				(type default)
			)
			(fill no)
			(layer "F.CrtYd")
		)
		(fp_rect
			(start -0.4318 0.9525)
			(end 0.4318 -0.9525)
			(stroke
				(width 0)
				(type default)
			)
			(fill no)
			(layer "F.Fab")
		)
		(pad "1" smd custom
			(at 0 -0.4445 90)
			(size 0.1524 0.1524)
			(layers "F.Cu" "F.Mask" "F.Paste")
			(net "P12V_B")
			(options
				(clearance outline)
				(anchor circle)
			)
			(primitives
				(gr_poly
					(pts
						(arc
							(start 0.3048 -0.2032)
							(mid 0.275042 -0.275042)
							(end 0.2032 -0.3048)
						)
						(arc
							(start -0.2032 -0.3048)
							(mid -0.275042 -0.275042)
							(end -0.3048 -0.2032)
						)
						(arc
							(start -0.3048 0.2032)
							(mid -0.275042 0.275042)
							(end -0.2032 0.3048)
						)
						(arc
							(start 0.2032 0.3048)
							(mid 0.275042 0.275042)
							(end 0.3048 0.2032)
						)
					)
					(width 0)
					(fill yes)
				)
			)
		)
		(pad "2" smd custom
			(at 0 0.4445 90)
			(size 0.1524 0.1524)
			(layers "F.Cu" "F.Mask" "F.Paste")
			(net "SW_HDD_N11")
			(options
				(clearance outline)
				(anchor circle)
			)
			(primitives
				(gr_poly
					(pts
						(arc
							(start 0.3048 -0.2032)
							(mid 0.275042 -0.275042)
							(end 0.2032 -0.3048)
						)
						(arc
							(start -0.2032 -0.3048)
							(mid -0.275042 -0.275042)
							(end -0.3048 -0.2032)
						)
						(arc
							(start -0.3048 0.2032)
							(mid -0.275042 0.275042)
							(end -0.2032 0.3048)
						)
						(arc
							(start 0.2032 0.3048)
							(mid 0.275042 0.275042)
							(end 0.3048 0.2032)
						)
					)
					(width 0)
					(fill yes)
				)
			)
		)
	)
	(footprint ""
		(layer "F.Cu")
		(at 253.604522 -360.146346 90)
		(property "Reference" "R1045"
			(at 0 0 90)
			(layer "F.SilkS")
			(hide yes)
			(effects
				(font
					(size 1.27 1.27)
				)
			)
		)
		(property "Value" "100KR2F-L1-GP"
			(at 0.064008 -3.993896 90)
			(unlocked yes)
			(layer "F.Fab")
			(hide yes)
			(effects
				(font
					(size 1.016 1.016)
					(thickness 0.1524)
				)
			)
		)
		(property "Device Type" "R402H16"
			(at 0.064008 -5.517896 90)
			(unlocked yes)
			(layer "F.Fab")
			(hide yes)
			(effects
				(font
					(size 1.016 1.016)
					(thickness 0.1524)
				)
			)
		)
		(duplicate_pad_numbers_are_jumpers no)
		(fp_line
			(start 0.508 -0.9398)
			(end -0.508 -0.9398)
			(stroke
				(width 0.1524)
				(type default)
			)
			(layer "F.SilkS")
		)
		(fp_line
			(start -0.508 -0.9398)
			(end -0.508 0.9398)
			(stroke
				(width 0.1524)
				(type default)
			)
			(layer "F.SilkS")
		)
		(fp_rect
			(start -0.508 0.9398)
			(end 0.508 -0.9398)
			(stroke
				(width 0)
				(type default)
			)
			(fill no)
			(layer "F.CrtYd")
		)
		(fp_rect
			(start -0.508 0.9398)
			(end 0.508 -0.9398)
			(stroke
				(width 0)
				(type default)
			)
			(fill no)
			(layer "F.Fab")
		)
		(pad "1" smd custom
			(at 0 -0.4445 90)
			(size 0.1397 0.1397)
			(layers "F.Cu" "F.Mask" "F.Paste")
			(net "MB3_VCAP_R")
			(options
				(clearance outline)
				(anchor circle)
			)
			(primitives
				(gr_poly
					(pts
						(arc
							(start -0.1778 -0.2794)
							(mid -0.249642 -0.249642)
							(end -0.2794 -0.1778)
						)
						(arc
							(start -0.2794 0.1778)
							(mid -0.249642 0.249642)
							(end -0.1778 0.2794)
						)
						(arc
							(start 0.1778 0.2794)
							(mid 0.249642 0.249642)
							(end 0.2794 0.1778)
						)
						(arc
							(start 0.2794 -0.1778)
							(mid 0.249642 -0.249642)
							(end 0.1778 -0.2794)
						)
					)
					(width 0)
					(fill yes)
				)
			)
		)
		(pad "2" smd custom
			(at 0 0.4445 90)
			(size 0.1397 0.1397)
			(layers "F.Cu" "F.Mask" "F.Paste")
			(net "MB3_ISTART_R")
			(options
				(clearance outline)
				(anchor circle)
			)
			(primitives
				(gr_poly
					(pts
						(arc
							(start -0.1778 -0.2794)
							(mid -0.249642 -0.249642)
							(end -0.2794 -0.1778)
						)
						(arc
							(start -0.2794 0.1778)
							(mid -0.249642 0.249642)
							(end -0.1778 0.2794)
						)
						(arc
							(start 0.1778 0.2794)
							(mid 0.249642 0.249642)
							(end 0.2794 0.1778)
						)
						(arc
							(start 0.2794 -0.1778)
							(mid 0.249642 -0.249642)
							(end 0.1778 -0.2794)
						)
					)
					(width 0)
					(fill yes)
				)
			)
		)
	)
	(footprint ""
		(layer "F.Cu")
		(at 396.621 -160.02 180)
		(property "Reference" "C295"
			(at 0 0 180)
			(layer "F.SilkS")
			(hide yes)
			(effects
				(font
					(size 1.27 1.27)
				)
			)
		)
		(property "Value" "SC4D7U25V5KX-1-GP"
			(at -0.0762 -6.1214 180)
			(unlocked yes)
			(layer "F.Fab")
			(hide yes)
			(effects
				(font
					(size 1.016 1.016)
					(thickness 0.1524)
				)
			)
		)
		(property "Device Type" "C805H58"
			(at -0.0762 -8.1534 180)
			(unlocked yes)
			(layer "F.Fab")
			(hide yes)
			(effects
				(font
					(size 1.016 1.016)
					(thickness 0.1524)
				)
			)
		)
		(duplicate_pad_numbers_are_jumpers no)
		(fp_line
			(start 0.635 0)
			(end -0.635 0)
			(stroke
				(width 0.508)
				(type default)
			)
			(layer "F.SilkS")
		)
		(fp_rect
			(start -0.9652 1.778)
			(end 0.9652 -1.778)
			(stroke
				(width 0)
				(type default)
			)
			(fill no)
			(layer "F.CrtYd")
		)
		(fp_poly
			(pts
				(xy -0.9652 -1.778) (xy 0.9652 -1.778) (xy 0.9652 1.778) (xy -0.9652 1.778)
			)
			(stroke
				(width 0)
				(type default)
			)
			(fill no)
			(layer "F.Fab")
		)
		(pad "1" smd rect
			(at 0 -0.9652 180)
			(size 1.397 1.143)
			(layers "F.Cu" "F.Mask" "F.Paste")
			(net "P12V_HDD20")
		)
		(pad "2" smd rect
			(at 0 0.9652 180)
			(size 1.397 1.143)
			(layers "F.Cu" "F.Mask" "F.Paste")
			(net "GND")
		)
	)
)
